# T6G (Grand Teton) — schematic netlist excerpt (pin names and nets, part order shuffled) for the footprints in the layout excerpt that follows; sources: Cadence DE-HDL packaged netlist, KiCad conversion of 04192023_DAF0TMB3IC0_F0TG_MB_C_brd_V02_OCP.brd

R6500  Q_RES  0 5% CHIP  pkg 0402LF  page 188 : A = PWRGD_P3V3_EN_R ; B = PWRGD_P3V3_EN

U44  74LVC1G17GW  IC  pkg TSSOP5  page 145
  NC  = NC
  A  = FM_LED_ACTIVE_E1S_0_R
  GND  = GND
  Y  = FM_LED_ACTIVE_E1S_0_R_BUF
  VCC  = P3V3_E1S_0

PL42  Q_INDUCTOR  50NH/86A IND  pkg SMLF  page 218 : \1\ = SW_P12V_AUX_PVDDCR_CPU1_P1_FLT ; \2\ = P12V_AUX

(kicad_pcb
	(version 20260206)
	(generator "pcbnew")
	(generator_version "10.0")
	(general
		(thickness 1.6)
		(legacy_teardrops no)
	)
	(paper "A4")
	(title_block
		(title "04192023_DAF0TMB3IC0_F0TG_MB_C_brd_V02_OCP.brd")
		(comment 1 "Grand Teton / footprints 551-553 of 8354")
	)
	(layers
		(0 "F.Cu" signal "TOP")
		(4 "In1.Cu" signal "GND")
		(6 "In2.Cu" signal "IN1")
		(8 "In3.Cu" signal "GND1")
		(10 "In4.Cu" signal "IN2")
		(12 "In5.Cu" signal "GND2")
		(14 "In6.Cu" signal "IN3")
		(16 "In7.Cu" signal "GND3")
		(18 "In8.Cu" signal "VCC")
		(20 "In9.Cu" signal "VCC1")
		(22 "In10.Cu" signal "GND4")
		(24 "In11.Cu" signal "IN4")
		(26 "In12.Cu" signal "GND5")
		(28 "In13.Cu" signal "IN5")
		(30 "In14.Cu" signal "GND6")
		(32 "In15.Cu" signal "IN6")
		(34 "In16.Cu" signal "GND7")
		(2 "B.Cu" signal "BOTTOM")
		(9 "F.Adhes" user "F.Adhesive")
		(11 "B.Adhes" user "B.Adhesive")
		(13 "F.Paste" user "Package Geometry/Pastemask Top")
		(15 "B.Paste" user "Package Geometry/Pastemask Bottom")
		(5 "F.SilkS" user "Ref Des/Silkscreen Top")
		(7 "B.SilkS" user "Ref Des/Silkscreen Bottom")
		(1 "F.Mask" user "Board Geometry/Soldermask Top")
		(3 "B.Mask" user "Board Geometry/Soldermask Bottom")
		(17 "Dwgs.User" user "User.Drawings")
		(19 "Cmts.User" user "User.Comments")
		(21 "Eco1.User" user "User.Eco1")
		(23 "Eco2.User" user "User.Eco2")
		(25 "Edge.Cuts" user "Board Geometry/Outline")
		(27 "Margin" user)
		(31 "F.CrtYd" user "Package Geometry/Place Bound Top")
		(29 "B.CrtYd" user "Package Geometry/Place Bound Bottom")
		(35 "F.Fab" user "Ref Des/Assembly Top")
		(33 "B.Fab" user "Ref Des/Assembly Bottom")
	)
	(footprint ""
		(layer "F.Cu")
		(at 111.633 -125.73 90)
		(property "Reference" "R6500"
			(at 0 0 90)
			(layer "F.SilkS")
			(hide yes)
			(effects
				(font
					(size 1.27 1.27)
				)
			)
		)
		(property "Value" ""
			(at 0 0 90)
			(layer "F.Fab")
			(effects
				(font
					(size 1.27 1.27)
				)
			)
		)
		(duplicate_pad_numbers_are_jumpers no)
		(fp_line
			(start 0.7874 -0.4064)
			(end 0.7874 0.4064)
			(stroke
				(width 0.1524)
				(type default)
			)
			(layer "F.SilkS")
		)
		(fp_line
			(start -0.7874 -0.4064)
			(end 0.7874 -0.4064)
			(stroke
				(width 0.1524)
				(type default)
			)
			(layer "F.SilkS")
		)
		(fp_line
			(start 0.7874 0.4064)
			(end -0.7874 0.4064)
			(stroke
				(width 0.1524)
				(type default)
			)
			(layer "F.SilkS")
		)
		(fp_line
			(start -0.7874 0.4064)
			(end -0.7874 -0.4064)
			(stroke
				(width 0.1524)
				(type default)
			)
			(layer "F.SilkS")
		)
		(fp_line
			(start -0.12065 -0.305054)
			(end -0.12065 -0.2794)
			(stroke
				(width 0.1)
				(type default)
			)
			(layer "F.Fab")
		)
		(fp_line
			(start -0.67945 -0.305054)
			(end -0.12065 -0.305054)
			(stroke
				(width 0.1)
				(type default)
			)
			(layer "F.Fab")
		)
		(fp_line
			(start 0.67945 -0.3048)
			(end 0.67945 0.3048)
			(stroke
				(width 0.1)
				(type default)
			)
			(layer "F.Fab")
		)
		(fp_line
			(start 0.12065 -0.3048)
			(end 0.67945 -0.3048)
			(stroke
				(width 0.1)
				(type default)
			)
			(layer "F.Fab")
		)
		(fp_line
			(start 0.12065 -0.2794)
			(end 0.12065 -0.3048)
			(stroke
				(width 0.1)
				(type default)
			)
			(layer "F.Fab")
		)
		(fp_line
			(start -0.12065 -0.2794)
			(end 0.12065 -0.2794)
			(stroke
				(width 0.1)
				(type default)
			)
			(layer "F.Fab")
		)
		(fp_line
			(start 0.120396 0.2794)
			(end -0.12065 0.2794)
			(stroke
				(width 0.1)
				(type default)
			)
			(layer "F.Fab")
		)
		(fp_line
			(start -0.12065 0.2794)
			(end -0.12065 0.3048)
			(stroke
				(width 0.1)
				(type default)
			)
			(layer "F.Fab")
		)
		(fp_line
			(start 0.67945 0.3048)
			(end 0.120396 0.3048)
			(stroke
				(width 0.1)
				(type default)
			)
			(layer "F.Fab")
		)
		(fp_line
			(start 0.120396 0.3048)
			(end 0.120396 0.2794)
			(stroke
				(width 0.1)
				(type default)
			)
			(layer "F.Fab")
		)
		(fp_line
			(start -0.12065 0.3048)
			(end -0.67945 0.3048)
			(stroke
				(width 0.1)
				(type default)
			)
			(layer "F.Fab")
		)
		(fp_line
			(start -0.67945 0.3048)
			(end -0.67945 -0.305054)
			(stroke
				(width 0.1)
				(type default)
			)
			(layer "F.Fab")
		)
		(pad "1" smd circle
			(at -0.40005 0 90)
			(size 0 0)
			(layers "F.Cu" "F.Mask" "F.Paste")
			(net "PWRGD_P3V3_EN_R")
		)
		(pad "2" smd circle
			(at 0.40005 0 90)
			(size 0 0)
			(layers "F.Cu" "F.Mask" "F.Paste")
			(net "PWRGD_P3V3_EN")
		)
	)
	(footprint ""
		(layer "F.Cu")
		(at 237.507272 -68.524374 180)
		(property "Reference" "U44"
			(at 1.378204 -2.10566 0)
			(unlocked yes)
			(layer "F.SilkS")
			(effects
				(font
					(size 0.7874 0.5842)
					(thickness 0.1524)
				)
				(justify left)
			)
		)
		(property "Value" ""
			(at 0 0 180)
			(layer "F.Fab")
			(effects
				(font
					(size 1.27 1.27)
				)
			)
		)
		(duplicate_pad_numbers_are_jumpers no)
		(fp_line
			(start 1.695958 1.124966)
			(end -1.695958 1.124966)
			(stroke
				(width 0.1524)
				(type default)
			)
			(layer "F.SilkS")
		)
		(fp_line
			(start 1.695958 -1.124966)
			(end 1.695958 1.124966)
			(stroke
				(width 0.1524)
				(type default)
			)
			(layer "F.SilkS")
		)
		(fp_line
			(start -1.695958 1.124966)
			(end -1.695958 -1.124966)
			(stroke
				(width 0.1524)
				(type default)
			)
			(layer "F.SilkS")
		)
		(fp_line
			(start -1.695958 -1.124966)
			(end 1.695958 -1.124966)
			(stroke
				(width 0.1524)
				(type default)
			)
			(layer "F.SilkS")
		)
		(fp_poly
			(pts
				(xy -2.4892 -0.340106) (xy -2.4892 -0.959866) (xy -1.86944 -0.649986)
			)
			(stroke
				(width 0)
				(type default)
			)
			(fill yes)
			(layer "F.SilkS")
		)
		(fp_line
			(start 0.674878 1.124966)
			(end -0.674878 1.124966)
			(stroke
				(width 0.1)
				(type default)
			)
			(layer "F.Fab")
		)
		(fp_line
			(start 0.674878 -1.124966)
			(end 0.674878 1.124966)
			(stroke
				(width 0.1)
				(type default)
			)
			(layer "F.Fab")
		)
		(fp_line
			(start -0.674878 1.124966)
			(end -0.674878 -1.124966)
			(stroke
				(width 0.1)
				(type default)
			)
			(layer "F.Fab")
		)
		(fp_line
			(start -0.674878 -1.124966)
			(end 0.674878 -1.124966)
			(stroke
				(width 0.1)
				(type default)
			)
			(layer "F.Fab")
		)
		(fp_poly
			(pts
				(xy -2.4892 -0.959866) (xy -1.86944 -0.649986) (xy -2.4892 -0.340106)
			)
			(stroke
				(width 0)
				(type default)
			)
			(fill yes)
			(layer "F.Fab")
		)
		(pad "1" smd rect
			(at -0.94488 -0.649986 270)
			(size 0.3556 1.2446)
			(layers "F.Cu" "F.Mask" "F.Paste")
			(net "Net_10764")
		)
		(pad "2" smd rect
			(at -0.94488 0 270)
			(size 0.3556 1.2446)
			(layers "F.Cu" "F.Mask" "F.Paste")
			(net "FM_LED_ACTIVE_E1S_0_R")
		)
		(pad "3" smd rect
			(at -0.94488 0.649986 270)
			(size 0.3556 1.2446)
			(layers "F.Cu" "F.Mask" "F.Paste")
			(net "GND")
		)
		(pad "4" smd rect
			(at 0.94488 0.649986 270)
			(size 0.3556 1.2446)
			(layers "F.Cu" "F.Mask" "F.Paste")
			(net "FM_LED_ACTIVE_E1S_0_R_BUF")
		)
		(pad "5" smd rect
			(at 0.94488 -0.649986 270)
			(size 0.3556 1.2446)
			(layers "F.Cu" "F.Mask" "F.Paste")
			(net "P3V3_E1S_0")
		)
	)
	(footprint ""
		(layer "F.Cu")
		(at 90.487754 -350.497394 90)
		(property "Reference" "PL42"
			(at -2.671064 3.492246 0)
			(unlocked yes)
			(layer "F.SilkS")
			(effects
				(font
					(size 0.7874 0.5842)
					(thickness 0.1524)
				)
				(justify left)
			)
		)
		(property "Value" ""
			(at 0 0 90)
			(layer "F.Fab")
			(effects
				(font
					(size 1.27 1.27)
				)
			)
		)
		(duplicate_pad_numbers_are_jumpers no)
		(fp_line
			(start 3.050032 -2.999994)
			(end -3.050032 -2.999994)
			(stroke
				(width 0.1524)
				(type default)
			)
			(layer "F.SilkS")
		)
		(fp_line
			(start -3.050032 -2.999994)
			(end -3.050032 -1.4478)
			(stroke
				(width 0.1524)
				(type default)
			)
			(layer "F.SilkS")
		)
		(fp_line
			(start 3.050032 -1.4478)
			(end 3.050032 -2.999994)
			(stroke
				(width 0.1524)
				(type default)
			)
			(layer "F.SilkS")
		)
		(fp_line
			(start -3.050032 1.4478)
			(end -3.050032 2.999994)
			(stroke
				(width 0.1524)
				(type default)
			)
			(layer "F.SilkS")
		)
		(fp_line
			(start 3.050032 2.999994)
			(end 3.050032 1.4478)
			(stroke
				(width 0.1524)
				(type default)
			)
			(layer "F.SilkS")
		)
		(fp_line
			(start -3.050032 2.999994)
			(end 3.050032 2.999994)
			(stroke
				(width 0.1524)
				(type default)
			)
			(layer "F.SilkS")
		)
		(fp_line
			(start 3.050032 -2.999994)
			(end -3.050032 -2.999994)
			(stroke
				(width 0.1)
				(type default)
			)
			(layer "F.Fab")
		)
		(fp_line
			(start -3.050032 -2.999994)
			(end -3.050032 2.999994)
			(stroke
				(width 0.1)
				(type default)
			)
			(layer "F.Fab")
		)
		(fp_line
			(start 3.050032 2.999994)
			(end 3.050032 -2.999994)
			(stroke
				(width 0.1)
				(type default)
			)
			(layer "F.Fab")
		)
		(fp_line
			(start -3.050032 2.999994)
			(end 3.050032 2.999994)
			(stroke
				(width 0.1)
				(type default)
			)
			(layer "F.Fab")
		)
		(pad "1" smd rect
			(at -2.525014 0 90)
			(size 1.651 2.6162)
			(layers "F.Cu" "F.Mask" "F.Paste")
			(net "SW_P12V_AUX_PVDDCR_CPU1_P1_FLT")
		)
		(pad "2" smd rect
			(at 2.525014 0 90)
			(size 1.651 2.6162)
			(layers "F.Cu" "F.Mask" "F.Paste")
			(net "P12V_AUX")
		)
	)
)
